(kicad_pcb
	(version 20241229)
	(generator "pcbnew")
	(generator_version "9.0")
	(general
		(thickness 1.62)
		(legacy_teardrops no)
	)
	(paper "A3")
	(title_block
		(title "COM Express 7 Baseboard")
		(date "2025-02-04")
		(rev "1.1.2")
		(company "Antmicro Ltd")
		(comment 1 "www.antmicro.com")
		(comment 9 "footprints 509-512 of 802")
	)
	(layers
		(0 "F.Cu" signal)
		(4 "In1.Cu" signal)
		(6 "In2.Cu" signal)
		(8 "In3.Cu" signal)
		(10 "In4.Cu" signal)
		(12 "In5.Cu" signal)
		(14 "In6.Cu" signal)
		(2 "B.Cu" signal)
		(9 "F.Adhes" user "F.Adhesive")
		(11 "B.Adhes" user "B.Adhesive")
		(13 "F.Paste" user)
		(15 "B.Paste" user)
		(5 "F.SilkS" user "F.Silkscreen")
		(7 "B.SilkS" user "B.Silkscreen")
		(1 "F.Mask" user)
		(3 "B.Mask" user)
		(17 "Dwgs.User" user "User.Drawings")
		(19 "Cmts.User" user "User.Comments")
		(21 "Eco1.User" user "User.Eco1")
		(23 "Eco2.User" user "User.Eco2")
		(25 "Edge.Cuts" user)
		(27 "Margin" user)
		(31 "F.CrtYd" user "F.Courtyard")
		(29 "B.CrtYd" user "B.Courtyard")
		(35 "F.Fab" user)
		(33 "B.Fab" user)
	)
	(footprint "antmicro-footprints:SOT-23-8"
		(layer "F.Cu")
		(at 303.15 92.56 -90)
		(descr "http://www.ti.com/lit/ds/symlink/ina219.pdf")
		(property "Reference" "U50"
			(at -1.1 -2.65 90)
			(layer "F.SilkS")
			(effects
				(font
					(size 0.7 0.7)
					(thickness 0.15)
				)
				(justify right bottom)
			)
		)
		(property "Value" "INA219AIDCNR"
			(at 0 2.8 90)
			(layer "F.Fab")
			(effects
				(font
					(size 0.7 0.7)
					(thickness 0.15)
				)
				(justify right bottom)
			)
		)
		(property "Datasheet" "https://www.ti.com/lit/ds/symlink/ina219.pdf?ts=1713856455637&ref_url=https%253A%252F%252Fwww.mouser.es%252F"
			(at 0 0 270)
			(layer "F.Fab")
			(hide yes)
			(effects
				(font
					(size 1.27 1.27)
					(thickness 0.15)
				)
			)
		)
		(property "Author" "Antmicro"
			(at 210.59 395.71 0)
			(layer "F.Fab")
			(hide yes)
			(effects
				(font
					(size 1 1)
					(thickness 0.15)
				)
			)
		)
		(property "License" "Apache-2.0"
			(at 210.59 395.71 0)
			(layer "F.Fab")
			(hide yes)
			(effects
				(font
					(size 1 1)
					(thickness 0.15)
				)
			)
		)
		(property "MPN" "INA219AIDCNR"
			(at 210.59 395.71 0)
			(layer "F.Fab")
			(hide yes)
			(effects
				(font
					(size 1 1)
					(thickness 0.15)
				)
			)
		)
		(property "Manufacturer" "Texas Instruments"
			(at 210.59 395.71 0)
			(layer "F.Fab")
			(hide yes)
			(effects
				(font
					(size 1 1)
					(thickness 0.15)
				)
			)
		)
		(sheetname "Power")
		(sheetfile "power.kicad_sch")
		(attr smd)
		(fp_line
			(start -0.987 1.6)
			(end -0.987 1.324)
			(stroke
				(width 0.15)
				(type solid)
			)
			(layer "F.SilkS")
		)
		(fp_line
			(start -0.613 1.6)
			(end -0.987 1.6)
			(stroke
				(width 0.15)
				(type solid)
			)
			(layer "F.SilkS")
		)
		(fp_line
			(start 1 1.6)
			(end 0.6 1.6)
			(stroke
				(width 0.15)
				(type solid)
			)
			(layer "F.SilkS")
		)
		(fp_line
			(start 1 1.3)
			(end 1 1.6)
			(stroke
				(width 0.15)
				(type solid)
			)
			(layer "F.SilkS")
		)
		(fp_line
			(start -1 -1.3)
			(end -1 -1.6)
			(stroke
				(width 0.15)
				(type solid)
			)
			(layer "F.SilkS")
		)
		(fp_line
			(start 1 -1.3)
			(end 1 -1.6)
			(stroke
				(width 0.15)
				(type solid)
			)
			(layer "F.SilkS")
		)
		(fp_line
			(start -1 -1.6)
			(end -0.6 -1.6)
			(stroke
				(width 0.15)
				(type solid)
			)
			(layer "F.SilkS")
		)
		(fp_line
			(start 1 -1.6)
			(end 0.625 -1.6)
			(stroke
				(width 0.15)
				(type solid)
			)
			(layer "F.SilkS")
		)
		(fp_circle
			(center -1.3 -1.4)
			(end -1.25 -1.4)
			(stroke
				(width 0.15)
				(type solid)
			)
			(fill yes)
			(layer "F.SilkS")
		)
		(fp_rect
			(start -1.9 -1.75)
			(end 1.898 1.75)
			(stroke
				(width 0.05)
				(type solid)
			)
			(fill no)
			(layer "F.CrtYd")
		)
		(fp_line
			(start -1.4 -1.25)
			(end -1.2 -1.45)
			(stroke
				(width 0.15)
				(type solid)
			)
			(layer "F.Fab")
		)
		(fp_rect
			(start -1.401 -1.45)
			(end 1.398 1.449)
			(stroke
				(width 0.15)
				(type solid)
			)
			(fill no)
			(layer "F.Fab")
		)
		(pad "1" smd roundrect
			(at -1.3 -0.975 180)
			(size 0.45 1.1)
			(layers "F.Cu" "F.Mask" "F.Paste")
			(roundrect_rratio 0.25)
			(net 75 "Net-(U50-IN+)")
			(pinfunction "IN+")
			(pintype "passive")
			(teardrops
				(best_length_ratio 0.2)
				(max_length 1)
				(best_width_ratio 0.9)
				(max_width 2)
				(curved_edges yes)
				(filter_ratio 0.9)
				(enabled yes)
				(allow_two_segments yes)
				(prefer_zone_connections yes)
			)
		)
		(pad "2" smd roundrect
			(at -1.3 -0.325 180)
			(size 0.45 1.1)
			(layers "F.Cu" "F.Mask" "F.Paste")
			(roundrect_rratio 0.25)
			(net 77 "+5V_AON")
			(pinfunction "IN-")
			(pintype "passive")
			(teardrops
				(best_length_ratio 0.2)
				(max_length 1)
				(best_width_ratio 0.9)
				(max_width 2)
				(curved_edges yes)
				(filter_ratio 0.9)
				(enabled yes)
				(allow_two_segments yes)
				(prefer_zone_connections yes)
			)
		)
		(pad "3" smd roundrect
			(at -1.3 0.325 180)
			(size 0.45 1.1)
			(layers "F.Cu" "F.Mask" "F.Paste")
			(roundrect_rratio 0.25)
			(net 1 "GND")
			(pinfunction "GND")
			(pintype "power_in")
			(teardrops
				(best_length_ratio 0.2)
				(max_length 1)
				(best_width_ratio 0.9)
				(max_width 2)
				(curved_edges yes)
				(filter_ratio 0.9)
				(enabled yes)
				(allow_two_segments yes)
				(prefer_zone_connections yes)
			)
		)
		(pad "4" smd roundrect
			(at -1.3 0.975 180)
			(size 0.45 1.1)
			(layers "F.Cu" "F.Mask" "F.Paste")
			(roundrect_rratio 0.25)
			(net 73 "+3V3_AON")
			(pinfunction "V_{S}")
			(pintype "power_in")
			(teardrops
				(best_length_ratio 0.2)
				(max_length 1)
				(best_width_ratio 0.9)
				(max_width 2)
				(curved_edges yes)
				(filter_ratio 0.9)
				(enabled yes)
				(allow_two_segments yes)
				(prefer_zone_connections yes)
			)
		)
		(pad "5" smd roundrect
			(at 1.3 0.975 180)
			(size 0.45 1.1)
			(layers "F.Cu" "F.Mask" "F.Paste")
			(roundrect_rratio 0.25)
			(net 371 "/Com Express 7 MGMT/I2C.SCL")
			(pinfunction "SCL")
			(pintype "open_collector")
			(teardrops
				(best_length_ratio 0.2)
				(max_length 1)
				(best_width_ratio 0.9)
				(max_width 2)
				(curved_edges yes)
				(filter_ratio 0.9)
				(enabled yes)
				(allow_two_segments yes)
				(prefer_zone_connections yes)
			)
		)
		(pad "6" smd roundrect
			(at 1.3 0.325 180)
			(size 0.45 1.1)
			(layers "F.Cu" "F.Mask" "F.Paste")
			(roundrect_rratio 0.25)
			(net 372 "/Com Express 7 MGMT/I2C.SDA")
			(pinfunction "SDA")
			(pintype "open_collector")
			(teardrops
				(best_length_ratio 0.2)
				(max_length 1)
				(best_width_ratio 0.9)
				(max_width 2)
				(curved_edges yes)
				(filter_ratio 0.9)
				(enabled yes)
				(allow_two_segments yes)
				(prefer_zone_connections yes)
			)
		)
		(pad "7" smd roundrect
			(at 1.3 -0.325 180)
			(size 0.45 1.1)
			(layers "F.Cu" "F.Mask" "F.Paste")
			(roundrect_rratio 0.25)
			(net 372 "/Com Express 7 MGMT/I2C.SDA")
			(pinfunction "A0")
			(pintype "passive")
			(teardrops
				(best_length_ratio 0.2)
				(max_length 1)
				(best_width_ratio 0.9)
				(max_width 2)
				(curved_edges yes)
				(filter_ratio 0.9)
				(enabled yes)
				(allow_two_segments yes)
				(prefer_zone_connections yes)
			)
		)
		(pad "8" smd roundrect
			(at 1.3 -0.975 180)
			(size 0.45 1.1)
			(layers "F.Cu" "F.Mask" "F.Paste")
			(roundrect_rratio 0.25)
			(net 1 "GND")
			(pinfunction "A1")
			(pintype "passive")
			(teardrops
				(best_length_ratio 0.2)
				(max_length 1)
				(best_width_ratio 0.9)
				(max_width 2)
				(curved_edges yes)
				(filter_ratio 0.9)
				(enabled yes)
				(allow_two_segments yes)
				(prefer_zone_connections yes)
			)
		)
	)
	(footprint "antmicro-footprints:C_0402_1005Metric"
		(layer "F.Cu")
		(at 252.92 165.53 180)
		(descr "Capacitor SMD 0402")
		(tags "capacitor SMD 0402")
		(property "Reference" "C105"
			(at -1.5 -0.5 0)
			(layer "F.SilkS")
			(effects
				(font
					(size 0.7 0.7)
					(thickness 0.15)
				)
				(justify right top)
			)
		)
		(property "Value" "C_100n_0402"
			(at -1.022927 2.155213 0)
			(layer "F.Fab")
			(effects
				(font
					(size 0.7 0.7)
					(thickness 0.15)
				)
				(justify right top)
			)
		)
		(property "Datasheet" "https://www.murata.com/products/productdetail?partno=GRM155R61H104KE14%23"
			(at 0 0 0)
			(layer "F.Fab")
			(hide yes)
			(effects
				(font
					(size 1.27 1.27)
					(thickness 0.15)
				)
			)
		)
		(property "Author" "Antmicro"
			(at 305.16 -23.74 90)
			(layer "F.Fab")
			(hide yes)
			(effects
				(font
					(size 1 1)
					(thickness 0.15)
				)
			)
		)
		(property "Dielectric" "X5R"
			(at 305.16 -23.74 90)
			(layer "F.Fab")
			(hide yes)
			(effects
				(font
					(size 1 1)
					(thickness 0.15)
				)
			)
		)
		(property "License" "Apache-2.0"
			(at 305.16 -23.74 90)
			(layer "F.Fab")
			(hide yes)
			(effects
				(font
					(size 1 1)
					(thickness 0.15)
				)
			)
		)
		(property "MPN" "GRM155R61H104KE14D"
			(at 305.16 -23.74 90)
			(layer "F.Fab")
			(hide yes)
			(effects
				(font
					(size 1 1)
					(thickness 0.15)
				)
			)
		)
		(property "Manufacturer" "Murata"
			(at 305.16 -23.74 90)
			(layer "F.Fab")
			(hide yes)
			(effects
				(font
					(size 1 1)
					(thickness 0.15)
				)
			)
		)
		(property "Public" "False"
			(at 305.16 -23.74 90)
			(layer "F.Fab")
			(hide yes)
			(effects
				(font
					(size 1 1)
					(thickness 0.15)
				)
			)
		)
		(property "Val" "100n"
			(at 305.16 -23.74 90)
			(layer "F.Fab")
			(hide yes)
			(effects
				(font
					(size 1 1)
					(thickness 0.15)
				)
			)
		)
		(property "Voltage" "50V"
			(at 305.16 -23.74 90)
			(layer "F.Fab")
			(hide yes)
			(effects
				(font
					(size 1 1)
					(thickness 0.15)
				)
			)
		)
		(sheetname "Com Express 7 MGMT")
		(sheetfile "com_express_7_mgmt.kicad_sch")
		(attr smd)
		(fp_rect
			(start -0.925 -0.47)
			(end 0.925 0.47)
			(stroke
				(width 0.05)
				(type default)
			)
			(fill no)
			(layer "F.CrtYd")
		)
		(fp_line
			(start 0.504 0.248)
			(end -0.494 0.248)
			(stroke
				(width 0.15)
				(type solid)
			)
			(layer "F.Fab")
		)
		(fp_line
			(start 0.504 -0.25)
			(end 0.504 0.248)
			(stroke
				(width 0.15)
				(type solid)
			)
			(layer "F.Fab")
		)
		(fp_line
			(start -0.494 0.248)
			(end -0.494 -0.25)
			(stroke
				(width 0.15)
				(type solid)
			)
			(layer "F.Fab")
		)
		(fp_line
			(start -0.494 -0.25)
			(end 0.504 -0.25)
			(stroke
				(width 0.15)
				(type solid)
			)
			(layer "F.Fab")
		)
		(pad "1" smd roundrect
			(at -0.48 0 180)
			(size 0.59 0.64)
			(layers "F.Cu" "F.Mask" "F.Paste")
			(roundrect_rratio 0.25)
			(net 1 "GND")
			(pintype "passive")
			(teardrops
				(best_length_ratio 0.2)
				(max_length 1)
				(best_width_ratio 0.9)
				(max_width 2)
				(curved_edges yes)
				(filter_ratio 0.9)
				(enabled yes)
				(allow_two_segments yes)
				(prefer_zone_connections yes)
			)
		)
		(pad "2" smd roundrect
			(at 0.48 0 180)
			(size 0.59 0.64)
			(layers "F.Cu" "F.Mask" "F.Paste")
			(roundrect_rratio 0.25)
			(net 85 "/Com Express 7 MGMT/MAFS_POWER")
			(pintype "passive")
			(teardrops
				(best_length_ratio 0.2)
				(max_length 1)
				(best_width_ratio 0.9)
				(max_width 2)
				(curved_edges yes)
				(filter_ratio 0.9)
				(enabled yes)
				(allow_two_segments yes)
				(prefer_zone_connections yes)
			)
		)
	)
	(footprint "antmicro-footprints:R_0201"
		(layer "F.Cu")
		(at 135.17 147.935 -90)
		(descr "Resistor SMD 0201")
		(tags "resistor SMD 0201")
		(property "Reference" "R283"
			(at 6.475 -0.58 270)
			(layer "F.SilkS")
			(effects
				(font
					(size 0.7 0.7)
					(thickness 0.15)
				)
				(justify left bottom)
			)
		)
		(property "Value" "R_0R_0201"
			(at 0 1.25 270)
			(layer "F.Fab")
			(effects
				(font
					(size 0.7 0.7)
					(thickness 0.15)
				)
				(justify left bottom)
			)
		)
		(property "Datasheet" "https://www.bourns.com/docs/product-datasheets/cr.pdf"
			(at 0 0 270)
			(layer "F.Fab")
			(hide yes)
			(effects
				(font
					(size 1.27 1.27)
					(thickness 0.15)
				)
			)
		)
		(property "Author" "Antmicro"
			(at -12.765 283.105 0)
			(layer "F.Fab")
			(hide yes)
			(effects
				(font
					(size 1 1)
					(thickness 0.15)
				)
			)
		)
		(property "License" "Apache-2.0"
			(at -12.765 283.105 0)
			(layer "F.Fab")
			(hide yes)
			(effects
				(font
					(size 1 1)
					(thickness 0.15)
				)
			)
		)
		(property "MPN" "CR0201-FX-0R00GLF"
			(at -12.765 283.105 0)
			(layer "F.Fab")
			(hide yes)
			(effects
				(font
					(size 1 1)
					(thickness 0.15)
				)
			)
		)
		(property "Manufacturer" "Bourns"
			(at -12.765 283.105 0)
			(layer "F.Fab")
			(hide yes)
			(effects
				(font
					(size 1 1)
					(thickness 0.15)
				)
			)
		)
		(property "Tolerance" "1%"
			(at -12.765 283.105 0)
			(layer "F.Fab")
			(hide yes)
			(effects
				(font
					(size 1 1)
					(thickness 0.15)
				)
			)
		)
		(property "Val" "0R"
			(at -12.765 283.105 0)
			(layer "F.Fab")
			(hide yes)
			(effects
				(font
					(size 1 1)
					(thickness 0.15)
				)
			)
		)
		(sheetname "KR to SFI #2")
		(sheetfile "kr_sfi.kicad_sch")
		(attr smd dnp)
		(fp_rect
			(start -0.7 -0.35)
			(end 0.7 0.35)
			(stroke
				(width 0.05)
				(type default)
			)
			(fill no)
			(layer "F.CrtYd")
		)
		(fp_rect
			(start -0.3 -0.15)
			(end 0.298 0.148)
			(stroke
				(width 0.15)
				(type solid)
			)
			(fill no)
			(layer "F.Fab")
		)
		(pad "" smd roundrect
			(at -0.346 0 270)
			(size 0.318 0.36)
			(layers "F.Paste")
			(roundrect_rratio 0.25)
			(teardrops
				(best_length_ratio 0.2)
				(max_length 1)
				(best_width_ratio 0.9)
				(max_width 2)
				(curved_edges yes)
				(filter_ratio 0.9)
				(enabled yes)
				(allow_two_segments yes)
				(prefer_zone_connections yes)
			)
		)
		(pad "" smd roundrect
			(at 0.344 0 270)
			(size 0.318 0.36)
			(layers "F.Paste")
			(roundrect_rratio 0.25)
			(teardrops
				(best_length_ratio 0.2)
				(max_length 1)
				(best_width_ratio 0.9)
				(max_width 2)
				(curved_edges yes)
				(filter_ratio 0.9)
				(enabled yes)
				(allow_two_segments yes)
				(prefer_zone_connections yes)
			)
		)
		(pad "1" smd roundrect
			(at -0.32 0 270)
			(size 0.46 0.4)
			(layers "F.Cu" "F.Mask")
			(roundrect_rratio 0.25)
			(net 427 "/2xSFP+/10GKR_SFP1.RX+")
			(pintype "passive")
			(teardrops
				(best_length_ratio 0.2)
				(max_length 1)
				(best_width_ratio 0.9)
				(max_width 2)
				(curved_edges yes)
				(filter_ratio 0.9)
				(enabled yes)
				(allow_two_segments yes)
				(prefer_zone_connections yes)
			)
		)
		(pad "2" smd roundrect
			(at 0.32 0 270)
			(size 0.46 0.4)
			(layers "F.Cu" "F.Mask")
			(roundrect_rratio 0.25)
			(net 949 "/2xSFP+/KR to SFI #2/BYP_RX+")
			(pintype "passive")
			(teardrops
				(best_length_ratio 0.2)
				(max_length 1)
				(best_width_ratio 0.9)
				(max_width 2)
				(curved_edges yes)
				(filter_ratio 0.9)
				(enabled yes)
				(allow_two_segments yes)
				(prefer_zone_connections yes)
			)
		)
	)
	(footprint "antmicro-footprints:R_0402_1005Metric"
		(layer "F.Cu")
		(at 263.25 92.437 90)
		(descr "Resistor SMD 0402")
		(tags "resistor SMD 0402")
		(property "Reference" "R147"
			(at 0.827 0.55 90)
			(layer "F.SilkS")
			(effects
				(font
					(size 0.7 0.7)
					(thickness 0.15)
				)
				(justify left bottom)
			)
		)
		(property "Value" "R_0R_0402"
			(at -1.011843 1.772047 90)
			(layer "F.Fab")
			(effects
				(font
					(size 0.7 0.7)
					(thickness 0.15)
				)
				(justify left bottom)
			)
		)
		(property "Datasheet" "https://industrial.panasonic.com/cdbs/www-data/pdf/RDA0000/AOA0000C301.pdf"
			(at 0 0 90)
			(layer "F.Fab")
			(hide yes)
			(effects
				(font
					(size 1.27 1.27)
					(thickness 0.15)
				)
			)
		)
		(property "Author" "Antmicro"
			(at 355.687 -170.813 0)
			(layer "F.Fab")
			(hide yes)
			(effects
				(font
					(size 1 1)
					(thickness 0.15)
				)
			)
		)
		(property "Current" "1A"
			(at 355.687 -170.813 0)
			(layer "F.Fab")
			(hide yes)
			(effects
				(font
					(size 1 1)
					(thickness 0.15)
				)
			)
		)
		(property "License" "Apache-2.0"
			(at 355.687 -170.813 0)
			(layer "F.Fab")
			(hide yes)
			(effects
				(font
					(size 1 1)
					(thickness 0.15)
				)
			)
		)
		(property "MPN" "ERJ2GE0R00X"
			(at 355.687 -170.813 0)
			(layer "F.Fab")
			(hide yes)
			(effects
				(font
					(size 1 1)
					(thickness 0.15)
				)
			)
		)
		(property "Manufacturer" "Panasonic"
			(at 355.687 -170.813 0)
			(layer "F.Fab")
			(hide yes)
			(effects
				(font
					(size 1 1)
					(thickness 0.15)
				)
			)
		)
		(property "Public" "False"
			(at 355.687 -170.813 0)
			(layer "F.Fab")
			(hide yes)
			(effects
				(font
					(size 1 1)
					(thickness 0.15)
				)
			)
		)
		(property "Tolerance" ""
			(at 355.687 -170.813 0)
			(layer "F.Fab")
			(hide yes)
			(effects
				(font
					(size 1 1)
					(thickness 0.15)
				)
			)
		)
		(property "Val" "0R"
			(at 355.687 -170.813 0)
			(layer "F.Fab")
			(hide yes)
			(effects
				(font
					(size 1 1)
					(thickness 0.15)
				)
			)
		)
		(sheetname "Misc")
		(sheetfile "misc.kicad_sch")
		(attr smd dnp)
		(fp_rect
			(start -0.925 -0.47)
			(end 0.925 0.47)
			(stroke
				(width 0.05)
				(type default)
			)
			(fill no)
			(layer "F.CrtYd")
		)
		(fp_rect
			(start -0.5 -0.25)
			(end 0.5 0.25)
			(stroke
				(width 0.15)
				(type solid)
			)
			(fill no)
			(layer "F.Fab")
		)
		(pad "1" smd roundrect
			(at -0.48 0 90)
			(size 0.59 0.64)
			(layers "F.Cu" "F.Mask" "F.Paste")
			(roundrect_rratio 0.25)
			(net 2 "+3V3")
			(pintype "passive")
			(teardrops
				(best_length_ratio 0.2)
				(max_length 1)
				(best_width_ratio 0.9)
				(max_width 2)
				(curved_edges yes)
				(filter_ratio 0.9)
				(enabled yes)
				(allow_two_segments yes)
				(prefer_zone_connections yes)
			)
		)
		(pad "2" smd roundrect
			(at 0.48 0 90)
			(size 0.59 0.64)
			(layers "F.Cu" "F.Mask" "F.Paste")
			(roundrect_rratio 0.25)
			(net 80 "Net-(Q6-D)")
			(pintype "passive")
			(teardrops
				(best_length_ratio 0.2)
				(max_length 1)
				(best_width_ratio 0.9)
				(max_width 2)
				(curved_edges yes)
				(filter_ratio 0.9)
				(enabled yes)
				(allow_two_segments yes)
				(prefer_zone_connections yes)
			)
		)
	)
)
